(kicad_pcb
	(version 20260206)
	(generator "pcbnew")
	(generator_version "10.0")
	(general
		(thickness 1.6)
		(legacy_teardrops no)
	)
	(paper "A4")
	(title_block
		(title "Bryce Canyon_R.DPB_16317-1_OCP.brd")
		(comment 1 "Bryce Canyon / footprints 581-587 of 2099")
	)
	(layers
		(0 "F.Cu" signal "TOP")
		(4 "In1.Cu" signal "L2GND")
		(6 "In2.Cu" signal "L3")
		(8 "In3.Cu" signal "L4VCC")
		(10 "In4.Cu" signal "L5VCC")
		(12 "In5.Cu" signal "L6")
		(14 "In6.Cu" signal "L7GND")
		(2 "B.Cu" signal "BOTTOM")
		(9 "F.Adhes" user "F.Adhesive")
		(11 "B.Adhes" user "B.Adhesive")
		(13 "F.Paste" user "Package Geometry/Pastemask Top")
		(15 "B.Paste" user "Package Geometry/Pastemask Bottom")
		(5 "F.SilkS" user "Ref Des/Silkscreen Top")
		(7 "B.SilkS" user "Ref Des/Silkscreen Bottom")
		(1 "F.Mask" user "Board Geometry/Soldermask Top")
		(3 "B.Mask" user "Board Geometry/Soldermask Bottom")
		(17 "Dwgs.User" user "User.Drawings")
		(19 "Cmts.User" user "User.Comments")
		(21 "Eco1.User" user "User.Eco1")
		(23 "Eco2.User" user "User.Eco2")
		(25 "Edge.Cuts" user "Board Geometry/Outline")
		(27 "Margin" user)
		(31 "F.CrtYd" user "Package Geometry/Place Bound Top")
		(29 "B.CrtYd" user "Package Geometry/Place Bound Bottom")
		(35 "F.Fab" user "Ref Des/Assembly Top")
		(33 "B.Fab" user "Ref Des/Assembly Bottom")
	)
	(footprint ""
		(layer "F.Cu")
		(at 268.097 -226.568)
		(property "Reference" "R9"
			(at 0 0 0)
			(layer "F.SilkS")
			(hide yes)
			(effects
				(font
					(size 1.27 1.27)
				)
			)
		)
		(property "Value" "1KR2F-3-GP"
			(at 0.064008 -3.993896 0)
			(unlocked yes)
			(layer "F.Fab")
			(hide yes)
			(effects
				(font
					(size 1.016 1.016)
					(thickness 0.1524)
				)
			)
		)
		(property "Device Type" "R402H16"
			(at 0.064008 -5.517896 0)
			(unlocked yes)
			(layer "F.Fab")
			(hide yes)
			(effects
				(font
					(size 1.016 1.016)
					(thickness 0.1524)
				)
			)
		)
		(duplicate_pad_numbers_are_jumpers no)
		(fp_line
			(start -0.508 -0.9398)
			(end -0.508 0.9398)
			(stroke
				(width 0.1524)
				(type default)
			)
			(layer "F.SilkS")
		)
		(fp_line
			(start 0.508 -0.9398)
			(end -0.508 -0.9398)
			(stroke
				(width 0.1524)
				(type default)
			)
			(layer "F.SilkS")
		)
		(fp_rect
			(start -0.508 0.9398)
			(end 0.508 -0.9398)
			(stroke
				(width 0)
				(type default)
			)
			(fill no)
			(layer "F.CrtYd")
		)
		(fp_rect
			(start -0.508 0.9398)
			(end 0.508 -0.9398)
			(stroke
				(width 0)
				(type default)
			)
			(fill no)
			(layer "F.Fab")
		)
		(pad "1" smd custom
			(at 0 -0.4445)
			(size 0.1397 0.1397)
			(layers "F.Cu" "F.Mask" "F.Paste")
			(net "P3V3_IN")
			(options
				(clearance outline)
				(anchor circle)
			)
			(primitives
				(gr_poly
					(pts
						(arc
							(start -0.1778 -0.2794)
							(mid -0.249642 -0.249642)
							(end -0.2794 -0.1778)
						)
						(arc
							(start -0.2794 0.1778)
							(mid -0.249642 0.249642)
							(end -0.1778 0.2794)
						)
						(arc
							(start 0.1778 0.2794)
							(mid 0.249642 0.249642)
							(end 0.2794 0.1778)
						)
						(arc
							(start 0.2794 -0.1778)
							(mid 0.249642 -0.249642)
							(end 0.1778 -0.2794)
						)
					)
					(width 0)
					(fill yes)
				)
			)
		)
		(pad "2" smd custom
			(at 0 0.4445)
			(size 0.1397 0.1397)
			(layers "F.Cu" "F.Mask" "F.Paste")
			(net "I2C_CLIP_B_SDA")
			(options
				(clearance outline)
				(anchor circle)
			)
			(primitives
				(gr_poly
					(pts
						(arc
							(start -0.1778 -0.2794)
							(mid -0.249642 -0.249642)
							(end -0.2794 -0.1778)
						)
						(arc
							(start -0.2794 0.1778)
							(mid -0.249642 0.249642)
							(end -0.1778 0.2794)
						)
						(arc
							(start 0.1778 0.2794)
							(mid 0.249642 0.249642)
							(end 0.2794 0.1778)
						)
						(arc
							(start 0.2794 -0.1778)
							(mid 0.249642 -0.249642)
							(end 0.1778 -0.2794)
						)
					)
					(width 0)
					(fill yes)
				)
			)
		)
	)
	(footprint ""
		(layer "F.Cu")
		(at 459.3082 -13.2588)
		(property "Reference" "R138"
			(at 0 0 0)
			(layer "F.SilkS")
			(hide yes)
			(effects
				(font
					(size 1.27 1.27)
				)
			)
		)
		(property "Value" "0R2J-2-GP"
			(at 0.064008 -3.993896 0)
			(unlocked yes)
			(layer "F.Fab")
			(hide yes)
			(effects
				(font
					(size 1.016 1.016)
					(thickness 0.1524)
				)
			)
		)
		(property "Device Type" "R402H16"
			(at 0.064008 -5.517896 0)
			(unlocked yes)
			(layer "F.Fab")
			(hide yes)
			(effects
				(font
					(size 1.016 1.016)
					(thickness 0.1524)
				)
			)
		)
		(duplicate_pad_numbers_are_jumpers no)
		(fp_line
			(start -0.508 -0.9398)
			(end -0.508 0.9398)
			(stroke
				(width 0.1524)
				(type default)
			)
			(layer "F.SilkS")
		)
		(fp_line
			(start 0.508 -0.9398)
			(end -0.508 -0.9398)
			(stroke
				(width 0.1524)
				(type default)
			)
			(layer "F.SilkS")
		)
		(fp_rect
			(start -0.508 0.9398)
			(end 0.508 -0.9398)
			(stroke
				(width 0)
				(type default)
			)
			(fill no)
			(layer "F.CrtYd")
		)
		(fp_rect
			(start -0.508 0.9398)
			(end 0.508 -0.9398)
			(stroke
				(width 0)
				(type default)
			)
			(fill no)
			(layer "F.Fab")
		)
		(pad "1" smd custom
			(at 0 -0.4445)
			(size 0.1397 0.1397)
			(layers "F.Cu" "F.Mask" "F.Paste")
			(net "I2C_DPB_B_SDA_BUF")
			(options
				(clearance outline)
				(anchor circle)
			)
			(primitives
				(gr_poly
					(pts
						(arc
							(start -0.1778 -0.2794)
							(mid -0.249642 -0.249642)
							(end -0.2794 -0.1778)
						)
						(arc
							(start -0.2794 0.1778)
							(mid -0.249642 0.249642)
							(end -0.1778 0.2794)
						)
						(arc
							(start 0.1778 0.2794)
							(mid 0.249642 0.249642)
							(end 0.2794 0.1778)
						)
						(arc
							(start 0.2794 -0.1778)
							(mid 0.249642 -0.249642)
							(end 0.1778 -0.2794)
						)
					)
					(width 0)
					(fill yes)
				)
			)
		)
		(pad "2" smd custom
			(at 0 0.4445)
			(size 0.1397 0.1397)
			(layers "F.Cu" "F.Mask" "F.Paste")
			(net "TEMP2_SDA")
			(options
				(clearance outline)
				(anchor circle)
			)
			(primitives
				(gr_poly
					(pts
						(arc
							(start -0.1778 -0.2794)
							(mid -0.249642 -0.249642)
							(end -0.2794 -0.1778)
						)
						(arc
							(start -0.2794 0.1778)
							(mid -0.249642 0.249642)
							(end -0.1778 0.2794)
						)
						(arc
							(start 0.1778 0.2794)
							(mid 0.249642 0.249642)
							(end 0.2794 0.1778)
						)
						(arc
							(start 0.2794 -0.1778)
							(mid 0.249642 -0.249642)
							(end 0.1778 -0.2794)
						)
					)
					(width 0)
					(fill yes)
				)
			)
		)
	)
	(footprint ""
		(layer "F.Cu")
		(at 18.415 -246.634)
		(property "Reference" "R915"
			(at 0 0 0)
			(layer "F.SilkS")
			(hide yes)
			(effects
				(font
					(size 1.27 1.27)
				)
			)
		)
		(property "Value" "0R2J-2-GP"
			(at 0.064008 -3.993896 0)
			(unlocked yes)
			(layer "F.Fab")
			(hide yes)
			(effects
				(font
					(size 1.016 1.016)
					(thickness 0.1524)
				)
			)
		)
		(property "Device Type" "R402H16"
			(at 0.064008 -5.517896 0)
			(unlocked yes)
			(layer "F.Fab")
			(hide yes)
			(effects
				(font
					(size 1.016 1.016)
					(thickness 0.1524)
				)
			)
		)
		(duplicate_pad_numbers_are_jumpers no)
		(fp_line
			(start -0.508 -0.9398)
			(end -0.508 0.9398)
			(stroke
				(width 0.1524)
				(type default)
			)
			(layer "F.SilkS")
		)
		(fp_line
			(start 0.508 -0.9398)
			(end -0.508 -0.9398)
			(stroke
				(width 0.1524)
				(type default)
			)
			(layer "F.SilkS")
		)
		(fp_rect
			(start -0.508 0.9398)
			(end 0.508 -0.9398)
			(stroke
				(width 0)
				(type default)
			)
			(fill no)
			(layer "F.CrtYd")
		)
		(fp_rect
			(start -0.508 0.9398)
			(end 0.508 -0.9398)
			(stroke
				(width 0)
				(type default)
			)
			(fill no)
			(layer "F.Fab")
		)
		(pad "1" smd custom
			(at 0 -0.4445)
			(size 0.1397 0.1397)
			(layers "F.Cu" "F.Mask" "F.Paste")
			(net "SW_HDD_G0")
			(options
				(clearance outline)
				(anchor circle)
			)
			(primitives
				(gr_poly
					(pts
						(arc
							(start -0.1778 -0.2794)
							(mid -0.249642 -0.249642)
							(end -0.2794 -0.1778)
						)
						(arc
							(start -0.2794 0.1778)
							(mid -0.249642 0.249642)
							(end -0.1778 0.2794)
						)
						(arc
							(start 0.1778 0.2794)
							(mid 0.249642 0.249642)
							(end 0.2794 0.1778)
						)
						(arc
							(start 0.2794 -0.1778)
							(mid 0.249642 -0.249642)
							(end 0.1778 -0.2794)
						)
					)
					(width 0)
					(fill yes)
				)
			)
		)
		(pad "2" smd custom
			(at 0 0.4445)
			(size 0.1397 0.1397)
			(layers "F.Cu" "F.Mask" "F.Paste")
			(net "SW_HDD_R0")
			(options
				(clearance outline)
				(anchor circle)
			)
			(primitives
				(gr_poly
					(pts
						(arc
							(start -0.1778 -0.2794)
							(mid -0.249642 -0.249642)
							(end -0.2794 -0.1778)
						)
						(arc
							(start -0.2794 0.1778)
							(mid -0.249642 0.249642)
							(end -0.1778 0.2794)
						)
						(arc
							(start 0.1778 0.2794)
							(mid 0.249642 0.249642)
							(end 0.2794 0.1778)
						)
						(arc
							(start 0.2794 -0.1778)
							(mid 0.249642 -0.249642)
							(end 0.1778 -0.2794)
						)
					)
					(width 0)
					(fill yes)
				)
			)
		)
	)
	(footprint ""
		(layer "F.Cu")
		(at 77.978 -24.511 -90)
		(property "Reference" "R683"
			(at 0 0 270)
			(layer "F.SilkS")
			(hide yes)
			(effects
				(font
					(size 1.27 1.27)
				)
			)
		)
		(property "Value" "300KR2F-GP"
			(at 0.064008 -3.993896 270)
			(unlocked yes)
			(layer "F.Fab")
			(hide yes)
			(effects
				(font
					(size 1.016 1.016)
					(thickness 0.1524)
				)
			)
		)
		(property "Device Type" "R402H16"
			(at 0.064008 -5.517896 270)
			(unlocked yes)
			(layer "F.Fab")
			(hide yes)
			(effects
				(font
					(size 1.016 1.016)
					(thickness 0.1524)
				)
			)
		)
		(duplicate_pad_numbers_are_jumpers no)
		(fp_line
			(start -0.508 -0.9398)
			(end -0.508 0.9398)
			(stroke
				(width 0.1524)
				(type default)
			)
			(layer "F.SilkS")
		)
		(fp_line
			(start 0.508 -0.9398)
			(end -0.508 -0.9398)
			(stroke
				(width 0.1524)
				(type default)
			)
			(layer "F.SilkS")
		)
		(fp_rect
			(start -0.508 0.9398)
			(end 0.508 -0.9398)
			(stroke
				(width 0)
				(type default)
			)
			(fill no)
			(layer "F.CrtYd")
		)
		(fp_rect
			(start -0.508 0.9398)
			(end 0.508 -0.9398)
			(stroke
				(width 0)
				(type default)
			)
			(fill no)
			(layer "F.Fab")
		)
		(pad "1" smd custom
			(at 0 -0.4445 270)
			(size 0.1397 0.1397)
			(layers "F.Cu" "F.Mask" "F.Paste")
			(net "SW_HDD_N26")
			(options
				(clearance outline)
				(anchor circle)
			)
			(primitives
				(gr_poly
					(pts
						(arc
							(start -0.1778 -0.2794)
							(mid -0.249642 -0.249642)
							(end -0.2794 -0.1778)
						)
						(arc
							(start -0.2794 0.1778)
							(mid -0.249642 0.249642)
							(end -0.1778 0.2794)
						)
						(arc
							(start 0.1778 0.2794)
							(mid 0.249642 0.249642)
							(end 0.2794 0.1778)
						)
						(arc
							(start 0.2794 -0.1778)
							(mid 0.249642 -0.249642)
							(end 0.1778 -0.2794)
						)
					)
					(width 0)
					(fill yes)
				)
			)
		)
		(pad "2" smd custom
			(at 0 0.4445 270)
			(size 0.1397 0.1397)
			(layers "F.Cu" "F.Mask" "F.Paste")
			(net "P12V_B")
			(options
				(clearance outline)
				(anchor circle)
			)
			(primitives
				(gr_poly
					(pts
						(arc
							(start -0.1778 -0.2794)
							(mid -0.249642 -0.249642)
							(end -0.2794 -0.1778)
						)
						(arc
							(start -0.2794 0.1778)
							(mid -0.249642 0.249642)
							(end -0.1778 0.2794)
						)
						(arc
							(start 0.1778 0.2794)
							(mid 0.249642 0.249642)
							(end 0.2794 0.1778)
						)
						(arc
							(start 0.2794 -0.1778)
							(mid 0.249642 -0.249642)
							(end 0.1778 -0.2794)
						)
					)
					(width 0)
					(fill yes)
				)
			)
		)
	)
	(footprint ""
		(layer "F.Cu")
		(at 459.613 -44.958 180)
		(property "Reference" "C478"
			(at 0 0 180)
			(layer "F.SilkS")
			(hide yes)
			(effects
				(font
					(size 1.27 1.27)
				)
			)
		)
		(property "Value" "SC4D7U25V5KX-1-GP"
			(at -0.0762 -6.1214 180)
			(unlocked yes)
			(layer "F.Fab")
			(hide yes)
			(effects
				(font
					(size 1.016 1.016)
					(thickness 0.1524)
				)
			)
		)
		(property "Device Type" "C805H58"
			(at -0.0762 -8.1534 180)
			(unlocked yes)
			(layer "F.Fab")
			(hide yes)
			(effects
				(font
					(size 1.016 1.016)
					(thickness 0.1524)
				)
			)
		)
		(duplicate_pad_numbers_are_jumpers no)
		(fp_line
			(start 0.635 0)
			(end -0.635 0)
			(stroke
				(width 0.508)
				(type default)
			)
			(layer "F.SilkS")
		)
		(fp_rect
			(start -0.9652 1.778)
			(end 0.9652 -1.778)
			(stroke
				(width 0)
				(type default)
			)
			(fill no)
			(layer "F.CrtYd")
		)
		(fp_poly
			(pts
				(xy -0.9652 -1.778) (xy 0.9652 -1.778) (xy 0.9652 1.778) (xy -0.9652 1.778)
			)
			(stroke
				(width 0)
				(type default)
			)
			(fill no)
			(layer "F.Fab")
		)
		(pad "1" smd rect
			(at 0 -0.9652 180)
			(size 1.397 1.143)
			(layers "F.Cu" "F.Mask" "F.Paste")
			(net "P12V_HDD34")
		)
		(pad "2" smd rect
			(at 0 0.9652 180)
			(size 1.397 1.143)
			(layers "F.Cu" "F.Mask" "F.Paste")
			(net "GND")
		)
	)
	(footprint ""
		(layer "F.Cu")
		(at 52.197 -11.4554 -90)
		(property "Reference" "R661"
			(at 0 0 270)
			(layer "F.SilkS")
			(hide yes)
			(effects
				(font
					(size 1.27 1.27)
				)
			)
		)
		(property "Value" "200KR2F-L-GP"
			(at 0.064008 -3.993896 270)
			(unlocked yes)
			(layer "F.Fab")
			(hide yes)
			(effects
				(font
					(size 1.016 1.016)
					(thickness 0.1524)
				)
			)
		)
		(property "Device Type" "R402H16"
			(at 0.064008 -5.517896 270)
			(unlocked yes)
			(layer "F.Fab")
			(hide yes)
			(effects
				(font
					(size 1.016 1.016)
					(thickness 0.1524)
				)
			)
		)
		(duplicate_pad_numbers_are_jumpers no)
		(fp_line
			(start -0.508 -0.9398)
			(end -0.508 0.9398)
			(stroke
				(width 0.1524)
				(type default)
			)
			(layer "F.SilkS")
		)
		(fp_line
			(start 0.508 -0.9398)
			(end -0.508 -0.9398)
			(stroke
				(width 0.1524)
				(type default)
			)
			(layer "F.SilkS")
		)
		(fp_rect
			(start -0.508 0.9398)
			(end 0.508 -0.9398)
			(stroke
				(width 0)
				(type default)
			)
			(fill no)
			(layer "F.CrtYd")
		)
		(fp_rect
			(start -0.508 0.9398)
			(end 0.508 -0.9398)
			(stroke
				(width 0)
				(type default)
			)
			(fill no)
			(layer "F.Fab")
		)
		(pad "1" smd custom
			(at 0 -0.4445 270)
			(size 0.1397 0.1397)
			(layers "F.Cu" "F.Mask" "F.Paste")
			(net "SW_HDD_R25")
			(options
				(clearance outline)
				(anchor circle)
			)
			(primitives
				(gr_poly
					(pts
						(arc
							(start -0.1778 -0.2794)
							(mid -0.249642 -0.249642)
							(end -0.2794 -0.1778)
						)
						(arc
							(start -0.2794 0.1778)
							(mid -0.249642 0.249642)
							(end -0.1778 0.2794)
						)
						(arc
							(start 0.1778 0.2794)
							(mid 0.249642 0.249642)
							(end 0.2794 0.1778)
						)
						(arc
							(start 0.2794 -0.1778)
							(mid 0.249642 -0.249642)
							(end 0.1778 -0.2794)
						)
					)
					(width 0)
					(fill yes)
				)
			)
		)
		(pad "2" smd custom
			(at 0 0.4445 270)
			(size 0.1397 0.1397)
			(layers "F.Cu" "F.Mask" "F.Paste")
			(net "SW_HDD_N25")
			(options
				(clearance outline)
				(anchor circle)
			)
			(primitives
				(gr_poly
					(pts
						(arc
							(start -0.1778 -0.2794)
							(mid -0.249642 -0.249642)
							(end -0.2794 -0.1778)
						)
						(arc
							(start -0.2794 0.1778)
							(mid -0.249642 0.249642)
							(end -0.1778 0.2794)
						)
						(arc
							(start 0.1778 0.2794)
							(mid 0.249642 0.249642)
							(end 0.2794 0.1778)
						)
						(arc
							(start 0.2794 -0.1778)
							(mid 0.249642 -0.249642)
							(end 0.1778 -0.2794)
						)
					)
					(width 0)
					(fill yes)
				)
			)
		)
	)
	(footprint ""
		(layer "F.Cu")
		(at 477.52 -19.685 -90)
		(property "Reference" "R875"
			(at 0 0 270)
			(layer "F.SilkS")
			(hide yes)
			(effects
				(font
					(size 1.27 1.27)
				)
			)
		)
		(property "Value" "10KR2F-2-GP"
			(at 0.064008 -3.993896 270)
			(unlocked yes)
			(layer "F.Fab")
			(hide yes)
			(effects
				(font
					(size 1.016 1.016)
					(thickness 0.1524)
				)
			)
		)
		(property "Device Type" "R402H16"
			(at 0.064008 -5.517896 270)
			(unlocked yes)
			(layer "F.Fab")
			(hide yes)
			(effects
				(font
					(size 1.016 1.016)
					(thickness 0.1524)
				)
			)
		)
		(duplicate_pad_numbers_are_jumpers no)
		(fp_line
			(start -0.508 -0.9398)
			(end -0.508 0.9398)
			(stroke
				(width 0.1524)
				(type default)
			)
			(layer "F.SilkS")
		)
		(fp_line
			(start 0.508 -0.9398)
			(end -0.508 -0.9398)
			(stroke
				(width 0.1524)
				(type default)
			)
			(layer "F.SilkS")
		)
		(fp_rect
			(start -0.508 0.9398)
			(end 0.508 -0.9398)
			(stroke
				(width 0)
				(type default)
			)
			(fill no)
			(layer "F.CrtYd")
		)
		(fp_rect
			(start -0.508 0.9398)
			(end 0.508 -0.9398)
			(stroke
				(width 0)
				(type default)
			)
			(fill no)
			(layer "F.Fab")
		)
		(pad "1" smd custom
			(at 0 -0.4445 270)
			(size 0.1397 0.1397)
			(layers "F.Cu" "F.Mask" "F.Paste")
			(net "P3V3_STBY_B")
			(options
				(clearance outline)
				(anchor circle)
			)
			(primitives
				(gr_poly
					(pts
						(arc
							(start -0.1778 -0.2794)
							(mid -0.249642 -0.249642)
							(end -0.2794 -0.1778)
						)
						(arc
							(start -0.2794 0.1778)
							(mid -0.249642 0.249642)
							(end -0.1778 0.2794)
						)
						(arc
							(start 0.1778 0.2794)
							(mid 0.249642 0.249642)
							(end 0.2794 0.1778)
						)
						(arc
							(start 0.2794 -0.1778)
							(mid 0.249642 -0.249642)
							(end 0.1778 -0.2794)
						)
					)
					(width 0)
					(fill yes)
				)
			)
		)
		(pad "2" smd custom
			(at 0 0.4445 270)
			(size 0.1397 0.1397)
			(layers "F.Cu" "F.Mask" "F.Paste")
			(net "HDD_PRSNT_35")
			(options
				(clearance outline)
				(anchor circle)
			)
			(primitives
				(gr_poly
					(pts
						(arc
							(start -0.1778 -0.2794)
							(mid -0.249642 -0.249642)
							(end -0.2794 -0.1778)
						)
						(arc
							(start -0.2794 0.1778)
							(mid -0.249642 0.249642)
							(end -0.1778 0.2794)
						)
						(arc
							(start 0.1778 0.2794)
							(mid 0.249642 0.249642)
							(end 0.2794 0.1778)
						)
						(arc
							(start 0.2794 -0.1778)
							(mid 0.249642 -0.249642)
							(end 0.1778 -0.2794)
						)
					)
					(width 0)
					(fill yes)
				)
			)
		)
	)
)
